(kicad_pcb
	(version 20260206)
	(generator "pcbnew")
	(generator_version "10.0")
	(general
		(thickness 1.6)
		(legacy_teardrops no)
	)
	(paper "A4")
	(title_block
		(title "Wiwynn_Tioga_Pass_MB.brd")
		(comment 1 "Tioga Pass / footprints 2968-2975 of 4770")
	)
	(layers
		(0 "F.Cu" signal "TOP")
		(4 "In1.Cu" signal "L2GND")
		(6 "In2.Cu" signal "L3")
		(8 "In3.Cu" signal "L4GND")
		(10 "In4.Cu" signal "L5")
		(12 "In5.Cu" signal "L6GND")
		(14 "In6.Cu" signal "L7VCC")
		(16 "In7.Cu" signal "L8VCC")
		(18 "In8.Cu" signal "L9GND")
		(20 "In9.Cu" signal "L10")
		(22 "In10.Cu" signal "L11GND")
		(24 "In11.Cu" signal "L12")
		(26 "In12.Cu" signal "L13GND")
		(2 "B.Cu" signal "BOTTOM")
		(9 "F.Adhes" user "F.Adhesive")
		(11 "B.Adhes" user "B.Adhesive")
		(13 "F.Paste" user "Package Geometry/Pastemask Top")
		(15 "B.Paste" user "Package Geometry/Pastemask Bottom")
		(5 "F.SilkS" user "Ref Des/Silkscreen Top")
		(7 "B.SilkS" user "Ref Des/Silkscreen Bottom")
		(1 "F.Mask" user "Board Geometry/Soldermask Top")
		(3 "B.Mask" user "Board Geometry/Soldermask Bottom")
		(17 "Dwgs.User" user "User.Drawings")
		(19 "Cmts.User" user "User.Comments")
		(21 "Eco1.User" user "User.Eco1")
		(23 "Eco2.User" user "User.Eco2")
		(25 "Edge.Cuts" user "Board Geometry/Outline")
		(27 "Margin" user)
		(31 "F.CrtYd" user "Package Geometry/Place Bound Top")
		(29 "B.CrtYd" user "Package Geometry/Place Bound Bottom")
		(35 "F.Fab" user "Ref Des/Assembly Top")
		(33 "B.Fab" user "Ref Des/Assembly Bottom")
	)
	(footprint ""
		(layer "B.Cu")
		(at 32.832802 -66.425064 90)
		(property "Reference" "C9P25"
			(at 0 0 90)
			(layer "B.SilkS")
			(hide yes)
			(effects
				(font
					(size 1.27 1.27)
				)
				(justify mirror)
			)
		)
		(property "Value" ""
			(at 0 0 90)
			(layer "B.Fab")
			(effects
				(font
					(size 1.27 1.27)
				)
				(justify mirror)
			)
		)
		(duplicate_pad_numbers_are_jumpers no)
		(fp_poly
			(pts
				(xy 0.7239 -0.2159) (xy -0.7239 -0.2159) (xy -0.7239 1.9939) (xy 0.7239 1.9939)
			)
			(stroke
				(width 0)
				(type default)
			)
			(fill no)
			(layer "B.CrtYd")
		)
		(fp_line
			(start 0.7239 -0.2159)
			(end 0.7239 1.9939)
			(stroke
				(width 0.1)
				(type default)
			)
			(layer "B.Fab")
		)
		(fp_line
			(start -0.7239 -0.2159)
			(end 0.7239 -0.2159)
			(stroke
				(width 0.1)
				(type default)
			)
			(layer "B.Fab")
		)
		(fp_line
			(start 0.7239 1.9939)
			(end -0.7239 1.9939)
			(stroke
				(width 0.1)
				(type default)
			)
			(layer "B.Fab")
		)
		(fp_line
			(start -0.7239 1.9939)
			(end -0.7239 -0.2159)
			(stroke
				(width 0.1)
				(type default)
			)
			(layer "B.Fab")
		)
		(pad "1" smd rect
			(at 0 0 270)
			(size 1.27 1.016)
			(layers "B.Cu" "B.Mask" "B.Paste")
			(net "VR_FET_SW_P12V_STBY_PVCCIN_CPU1")
		)
		(pad "2" smd rect
			(at 0 1.778 270)
			(size 1.27 1.016)
			(layers "B.Cu" "B.Mask" "B.Paste")
			(net "GND")
		)
		(zone
			(layer "B.Cu")
			(hatch none 0.5)
			(connect_pads
				(clearance 0)
			)
			(min_thickness 0.25)
			(keepout
				(tracks not_allowed)
				(vias allowed)
				(pads allowed)
				(copperpour not_allowed)
				(footprints allowed)
			)
			(placement
				(enabled no)
				(sheetname "")
			)
			(fill
				(thermal_gap 0.5)
				(thermal_bridge_width 0.5)
				(island_removal_mode 0)
			)
			(polygon
				(pts
					(xy 33.340802 -67.060064) (xy 33.340802 -65.790064) (xy 34.102802 -65.790064) (xy 34.102802 -67.060064)
				)
			)
		)
	)
	(footprint ""
		(layer "B.Cu")
		(at 402.4503 -38.7604 -90)
		(property "Reference" "R2U7"
			(at 0 0 90)
			(layer "B.SilkS")
			(hide yes)
			(effects
				(font
					(size 1.27 1.27)
				)
				(justify mirror)
			)
		)
		(property "Value" ""
			(at 0 0 90)
			(layer "B.Fab")
			(effects
				(font
					(size 1.27 1.27)
				)
				(justify mirror)
			)
		)
		(duplicate_pad_numbers_are_jumpers no)
		(fp_poly
			(pts
				(xy 0.2794 -0.1016) (xy -0.2794 -0.1016) (xy -0.2794 0.9906) (xy 0.2794 0.9906)
			)
			(stroke
				(width 0)
				(type default)
			)
			(fill no)
			(layer "B.CrtYd")
		)
		(fp_line
			(start -0.2794 0.9906)
			(end -0.2794 -0.1016)
			(stroke
				(width 0.1)
				(type default)
			)
			(layer "B.Fab")
		)
		(fp_line
			(start 0.2794 0.9906)
			(end -0.2794 0.9906)
			(stroke
				(width 0.1)
				(type default)
			)
			(layer "B.Fab")
		)
		(fp_line
			(start -0.2794 -0.1016)
			(end 0.2794 -0.1016)
			(stroke
				(width 0.1)
				(type default)
			)
			(layer "B.Fab")
		)
		(fp_line
			(start 0.2794 -0.1016)
			(end 0.2794 0.9906)
			(stroke
				(width 0.1)
				(type default)
			)
			(layer "B.Fab")
		)
		(pad "1" smd rect
			(at 0 0 90)
			(size 0.508 0.508)
			(layers "B.Cu" "B.Mask" "B.Paste")
			(net "SMB_OCP_FRU_STBY_LVC3_SCL_R")
		)
		(pad "2" smd rect
			(at 0 0.889 90)
			(size 0.508 0.508)
			(layers "B.Cu" "B.Mask" "B.Paste")
			(net "SMB_OCP_FRU_STBY_LVC3_SCL")
		)
		(zone
			(layer "B.Cu")
			(hatch none 0.5)
			(connect_pads
				(clearance 0)
			)
			(min_thickness 0.25)
			(keepout
				(tracks not_allowed)
				(vias allowed)
				(pads allowed)
				(copperpour not_allowed)
				(footprints allowed)
			)
			(placement
				(enabled no)
				(sheetname "")
			)
			(fill
				(thermal_gap 0.5)
				(thermal_bridge_width 0.5)
				(island_removal_mode 0)
			)
			(polygon
				(pts
					(xy 401.8153 -38.5064) (xy 401.8153 -39.0144) (xy 402.1963 -39.0144) (xy 402.1963 -38.5064)
				)
			)
		)
		(zone
			(layer "B.Cu")
			(hatch none 0.5)
			(connect_pads
				(clearance 0)
			)
			(min_thickness 0.25)
			(keepout
				(tracks allowed)
				(vias not_allowed)
				(pads allowed)
				(copperpour not_allowed)
				(footprints allowed)
			)
			(placement
				(enabled no)
				(sheetname "")
			)
			(fill
				(thermal_gap 0.5)
				(thermal_bridge_width 0.5)
				(island_removal_mode 0)
			)
			(polygon
				(pts
					(xy 402.1963 -38.5064) (xy 402.1963 -39.0144) (xy 401.8153 -39.0144) (xy 401.8153 -38.5064)
				)
			)
		)
	)
	(footprint ""
		(layer "B.Cu")
		(at 197.848728 -64.676782 90)
		(property "Reference" "C6R4"
			(at 0 0 90)
			(layer "B.SilkS")
			(hide yes)
			(effects
				(font
					(size 1.27 1.27)
				)
				(justify mirror)
			)
		)
		(property "Value" ""
			(at 0 0 90)
			(layer "B.Fab")
			(effects
				(font
					(size 1.27 1.27)
				)
				(justify mirror)
			)
		)
		(duplicate_pad_numbers_are_jumpers no)
		(fp_rect
			(start -0.7239 -0.2159)
			(end 0.7239 1.9939)
			(stroke
				(width 0)
				(type default)
			)
			(fill no)
			(layer "B.CrtYd")
		)
		(fp_line
			(start 0.7239 -0.2159)
			(end 0.7239 1.9939)
			(stroke
				(width 0.1)
				(type default)
			)
			(layer "B.Fab")
		)
		(fp_line
			(start -0.7239 -0.2159)
			(end 0.7239 -0.2159)
			(stroke
				(width 0.1)
				(type default)
			)
			(layer "B.Fab")
		)
		(fp_line
			(start 0.7239 1.9939)
			(end -0.7239 1.9939)
			(stroke
				(width 0.1)
				(type default)
			)
			(layer "B.Fab")
		)
		(fp_line
			(start -0.7239 1.9939)
			(end -0.7239 -0.2159)
			(stroke
				(width 0.1)
				(type default)
			)
			(layer "B.Fab")
		)
		(pad "1" smd rect
			(at 0 0 270)
			(size 1.27 1.016)
			(layers "B.Cu" "B.Mask" "B.Paste")
			(net "VR_FET_SW_P12V_STBY_PVCCIN_CPU0")
		)
		(pad "2" smd rect
			(at 0 1.778 270)
			(size 1.27 1.016)
			(layers "B.Cu" "B.Mask" "B.Paste")
			(net "GND")
		)
		(zone
			(layer "B.Cu")
			(hatch none 0.5)
			(connect_pads
				(clearance 0)
			)
			(min_thickness 0.25)
			(keepout
				(tracks not_allowed)
				(vias allowed)
				(pads allowed)
				(copperpour not_allowed)
				(footprints allowed)
			)
			(placement
				(enabled no)
				(sheetname "")
			)
			(fill
				(thermal_gap 0.5)
				(thermal_bridge_width 0.5)
				(island_removal_mode 0)
			)
			(polygon
				(pts
					(xy 198.356728 -64.041782) (xy 199.118728 -64.041782) (xy 199.118728 -65.311782) (xy 198.356728 -65.311782)
				)
			)
		)
	)
	(footprint ""
		(layer "B.Cu")
		(at 450.317362 -29.314648)
		(property "Reference" "C25W17"
			(at 0 0 0)
			(layer "B.SilkS")
			(hide yes)
			(effects
				(font
					(size 1.27 1.27)
				)
				(justify mirror)
			)
		)
		(property "Value" "*"
			(at 0 -2.9337 0)
			(unlocked yes)
			(layer "B.Fab")
			(hide yes)
			(effects
				(font
					(size 1.27 1.016)
					(thickness 0.1524)
				)
				(justify mirror)
			)
		)
		(property "Device Type" "SC1U16V3KX-2GP_SMD-BCG-SC1U16VA"
			(at 0 -4.4577 0)
			(unlocked yes)
			(layer "B.Fab")
			(hide yes)
			(effects
				(font
					(size 1.27 1.016)
					(thickness 0.1524)
				)
				(justify mirror)
			)
		)
		(duplicate_pad_numbers_are_jumpers no)
		(fp_line
			(start -0.508 0)
			(end 0.508 0)
			(stroke
				(width 0.2032)
				(type default)
			)
			(layer "B.SilkS")
		)
		(fp_rect
			(start 0.5842 1.3335)
			(end -0.5842 -1.3335)
			(stroke
				(width 0)
				(type default)
			)
			(fill no)
			(layer "B.CrtYd")
		)
		(fp_rect
			(start 0.5842 1.3335)
			(end -0.5842 -1.3335)
			(stroke
				(width 0)
				(type default)
			)
			(fill no)
			(layer "B.Fab")
		)
		(pad "1" smd custom
			(at 0 -0.762 180)
			(size 0.2159 0.2159)
			(layers "B.Cu" "B.Mask" "B.Paste")
			(net "P1V2_AUX_BMC")
			(options
				(clearance outline)
				(anchor circle)
			)
			(primitives
				(gr_poly
					(pts
						(arc
							(start -0.3302 0.4318)
							(mid -0.402042 0.402042)
							(end -0.4318 0.3302)
						)
						(arc
							(start -0.4318 -0.3302)
							(mid -0.402042 -0.402042)
							(end -0.3302 -0.4318)
						)
						(arc
							(start 0.3302 -0.4318)
							(mid 0.402042 -0.402042)
							(end 0.4318 -0.3302)
						)
						(arc
							(start 0.4318 0.3302)
							(mid 0.402042 0.402042)
							(end 0.3302 0.4318)
						)
					)
					(width 0)
					(fill yes)
				)
			)
		)
		(pad "2" smd custom
			(at 0 0.762 180)
			(size 0.2159 0.2159)
			(layers "B.Cu" "B.Mask" "B.Paste")
			(net "GND")
			(options
				(clearance outline)
				(anchor circle)
			)
			(primitives
				(gr_poly
					(pts
						(arc
							(start -0.3302 0.4318)
							(mid -0.402042 0.402042)
							(end -0.4318 0.3302)
						)
						(arc
							(start -0.4318 -0.3302)
							(mid -0.402042 -0.402042)
							(end -0.3302 -0.4318)
						)
						(arc
							(start 0.3302 -0.4318)
							(mid 0.402042 -0.402042)
							(end 0.4318 -0.3302)
						)
						(arc
							(start 0.4318 0.3302)
							(mid 0.402042 0.402042)
							(end 0.3302 0.4318)
						)
					)
					(width 0)
					(fill yes)
				)
			)
		)
	)
	(footprint ""
		(layer "B.Cu")
		(at 350.110806 -61.257434)
		(property "Reference" "C2U15"
			(at 0 0 0)
			(layer "B.SilkS")
			(hide yes)
			(effects
				(font
					(size 1.27 1.27)
				)
				(justify mirror)
			)
		)
		(property "Value" ""
			(at 0 0 0)
			(layer "B.Fab")
			(effects
				(font
					(size 1.27 1.27)
				)
				(justify mirror)
			)
		)
		(duplicate_pad_numbers_are_jumpers no)
		(fp_poly
			(pts
				(xy -0.3048 -0.1016) (xy -0.3048 0.9906) (xy 0.3048 0.9906) (xy 0.3048 -0.1016)
			)
			(stroke
				(width 0)
				(type default)
			)
			(fill no)
			(layer "B.CrtYd")
		)
		(fp_line
			(start -0.3048 -0.1016)
			(end 0.3048 -0.1016)
			(stroke
				(width 0.1)
				(type default)
			)
			(layer "B.Fab")
		)
		(fp_line
			(start -0.3048 0.9906)
			(end -0.3048 -0.1016)
			(stroke
				(width 0.1)
				(type default)
			)
			(layer "B.Fab")
		)
		(fp_line
			(start 0.3048 -0.1016)
			(end 0.3048 0.9906)
			(stroke
				(width 0.1)
				(type default)
			)
			(layer "B.Fab")
		)
		(fp_line
			(start 0.3048 0.9906)
			(end -0.3048 0.9906)
			(stroke
				(width 0.1)
				(type default)
			)
			(layer "B.Fab")
		)
		(pad "1" smd rect
			(at 0 0 180)
			(size 0.508 0.508)
			(layers "B.Cu" "B.Mask" "B.Paste")
			(net "P3E_CPU0_PE1_PCH_RXP<6>")
		)
		(pad "2" smd rect
			(at 0 0.889 180)
			(size 0.508 0.508)
			(layers "B.Cu" "B.Mask" "B.Paste")
			(net "P3E_CPU0_PE1_SS_RXP<6>")
		)
		(zone
			(layer "B.Cu")
			(hatch none 0.5)
			(connect_pads
				(clearance 0)
			)
			(min_thickness 0.25)
			(keepout
				(tracks allowed)
				(vias not_allowed)
				(pads allowed)
				(copperpour not_allowed)
				(footprints allowed)
			)
			(placement
				(enabled no)
				(sheetname "")
			)
			(fill
				(thermal_gap 0.5)
				(thermal_bridge_width 0.5)
				(island_removal_mode 0)
			)
			(polygon
				(pts
					(xy 350.364806 -61.003434) (xy 349.856806 -61.003434) (xy 349.856806 -60.622434) (xy 350.364806 -60.622434)
				)
			)
		)
		(zone
			(layer "B.Cu")
			(hatch none 0.5)
			(connect_pads
				(clearance 0)
			)
			(min_thickness 0.25)
			(keepout
				(tracks not_allowed)
				(vias allowed)
				(pads allowed)
				(copperpour not_allowed)
				(footprints allowed)
			)
			(placement
				(enabled no)
				(sheetname "")
			)
			(fill
				(thermal_gap 0.5)
				(thermal_bridge_width 0.5)
				(island_removal_mode 0)
			)
			(polygon
				(pts
					(xy 350.364806 -60.622434) (xy 349.856806 -60.622434) (xy 349.856806 -61.003434) (xy 350.364806 -61.003434)
				)
			)
		)
	)
	(footprint ""
		(layer "B.Cu")
		(at 183.16702 -10.91057 90)
		(property "Reference" "C6U7"
			(at -1.47828 0.78994 180)
			(unlocked yes)
			(layer "B.SilkS")
			(effects
				(font
					(size 0.4064 0.254)
					(thickness 0.1524)
				)
				(justify mirror)
			)
		)
		(property "Value" ""
			(at 0 0 90)
			(layer "B.Fab")
			(effects
				(font
					(size 1.27 1.27)
				)
				(justify mirror)
			)
		)
		(duplicate_pad_numbers_are_jumpers no)
		(fp_poly
			(pts
				(xy 0.7239 -0.2159) (xy -0.7239 -0.2159) (xy -0.7239 1.9939) (xy 0.7239 1.9939)
			)
			(stroke
				(width 0)
				(type default)
			)
			(fill no)
			(layer "B.CrtYd")
		)
		(fp_line
			(start 0.7239 -0.2159)
			(end 0.7239 1.9939)
			(stroke
				(width 0.1)
				(type default)
			)
			(layer "B.Fab")
		)
		(fp_line
			(start -0.7239 -0.2159)
			(end 0.7239 -0.2159)
			(stroke
				(width 0.1)
				(type default)
			)
			(layer "B.Fab")
		)
		(fp_line
			(start 0.7239 1.9939)
			(end -0.7239 1.9939)
			(stroke
				(width 0.1)
				(type default)
			)
			(layer "B.Fab")
		)
		(fp_line
			(start -0.7239 1.9939)
			(end -0.7239 -0.2159)
			(stroke
				(width 0.1)
				(type default)
			)
			(layer "B.Fab")
		)
		(pad "1" smd rect
			(at 0 0 270)
			(size 1.27 1.016)
			(layers "B.Cu" "B.Mask" "B.Paste")
			(net "VR_FET_SW_P12V_STBY_PVPP_GHJ")
		)
		(pad "2" smd rect
			(at 0 1.778 270)
			(size 1.27 1.016)
			(layers "B.Cu" "B.Mask" "B.Paste")
			(net "GND")
		)
		(zone
			(layer "B.Cu")
			(hatch none 0.5)
			(connect_pads
				(clearance 0)
			)
			(min_thickness 0.25)
			(keepout
				(tracks not_allowed)
				(vias allowed)
				(pads allowed)
				(copperpour not_allowed)
				(footprints allowed)
			)
			(placement
				(enabled no)
				(sheetname "")
			)
			(fill
				(thermal_gap 0.5)
				(thermal_bridge_width 0.5)
				(island_removal_mode 0)
			)
			(polygon
				(pts
					(xy 183.67502 -11.54557) (xy 183.67502 -10.27557) (xy 184.43702 -10.27557) (xy 184.43702 -11.54557)
				)
			)
		)
	)
	(footprint ""
		(layer "B.Cu")
		(at 389.382 -87.4395)
		(property "Reference" "R2N31"
			(at 0 0 0)
			(layer "B.SilkS")
			(hide yes)
			(effects
				(font
					(size 1.27 1.27)
				)
				(justify mirror)
			)
		)
		(property "Value" ""
			(at 0 0 0)
			(layer "B.Fab")
			(effects
				(font
					(size 1.27 1.27)
				)
				(justify mirror)
			)
		)
		(duplicate_pad_numbers_are_jumpers no)
		(fp_poly
			(pts
				(xy 0.2794 -0.1016) (xy -0.2794 -0.1016) (xy -0.2794 0.9906) (xy 0.2794 0.9906)
			)
			(stroke
				(width 0)
				(type default)
			)
			(fill no)
			(layer "B.CrtYd")
		)
		(fp_line
			(start -0.2794 -0.1016)
			(end 0.2794 -0.1016)
			(stroke
				(width 0.1)
				(type default)
			)
			(layer "B.Fab")
		)
		(fp_line
			(start -0.2794 0.9906)
			(end -0.2794 -0.1016)
			(stroke
				(width 0.1)
				(type default)
			)
			(layer "B.Fab")
		)
		(fp_line
			(start 0.2794 -0.1016)
			(end 0.2794 0.9906)
			(stroke
				(width 0.1)
				(type default)
			)
			(layer "B.Fab")
		)
		(fp_line
			(start 0.2794 0.9906)
			(end -0.2794 0.9906)
			(stroke
				(width 0.1)
				(type default)
			)
			(layer "B.Fab")
		)
		(pad "1" smd rect
			(at 0 0 180)
			(size 0.508 0.508)
			(layers "B.Cu" "B.Mask" "B.Paste")
			(net "SGPIO_PCH_SATA_CLOCK")
		)
		(pad "2" smd rect
			(at 0 0.889 180)
			(size 0.508 0.508)
			(layers "B.Cu" "B.Mask" "B.Paste")
			(net "SGPIO_PCH_SATA_CLOCK_R")
		)
		(zone
			(layer "B.Cu")
			(hatch none 0.5)
			(connect_pads
				(clearance 0)
			)
			(min_thickness 0.25)
			(keepout
				(tracks allowed)
				(vias not_allowed)
				(pads allowed)
				(copperpour not_allowed)
				(footprints allowed)
			)
			(placement
				(enabled no)
				(sheetname "")
			)
			(fill
				(thermal_gap 0.5)
				(thermal_bridge_width 0.5)
				(island_removal_mode 0)
			)
			(polygon
				(pts
					(xy 389.636 -87.1855) (xy 389.128 -87.1855) (xy 389.128 -86.8045) (xy 389.636 -86.8045)
				)
			)
		)
		(zone
			(layer "B.Cu")
			(hatch none 0.5)
			(connect_pads
				(clearance 0)
			)
			(min_thickness 0.25)
			(keepout
				(tracks not_allowed)
				(vias allowed)
				(pads allowed)
				(copperpour not_allowed)
				(footprints allowed)
			)
			(placement
				(enabled no)
				(sheetname "")
			)
			(fill
				(thermal_gap 0.5)
				(thermal_bridge_width 0.5)
				(island_removal_mode 0)
			)
			(polygon
				(pts
					(xy 389.636 -86.8045) (xy 389.128 -86.8045) (xy 389.128 -87.1855) (xy 389.636 -87.1855)
				)
			)
		)
	)
	(footprint ""
		(layer "B.Cu")
		(at 390.7155 -39.51351 -90)
		(property "Reference" "C2T2"
			(at 0 0 90)
			(layer "B.SilkS")
			(hide yes)
			(effects
				(font
					(size 1.27 1.27)
				)
				(justify mirror)
			)
		)
		(property "Value" ""
			(at 0 0 90)
			(layer "B.Fab")
			(effects
				(font
					(size 1.27 1.27)
				)
				(justify mirror)
			)
		)
		(duplicate_pad_numbers_are_jumpers no)
		(fp_poly
			(pts
				(xy -0.3048 -0.1016) (xy -0.3048 0.9906) (xy 0.3048 0.9906) (xy 0.3048 -0.1016)
			)
			(stroke
				(width 0)
				(type default)
			)
			(fill no)
			(layer "B.CrtYd")
		)
		(fp_line
			(start -0.3048 0.9906)
			(end -0.3048 -0.1016)
			(stroke
				(width 0.1)
				(type default)
			)
			(layer "B.Fab")
		)
		(fp_line
			(start 0.3048 0.9906)
			(end -0.3048 0.9906)
			(stroke
				(width 0.1)
				(type default)
			)
			(layer "B.Fab")
		)
		(fp_line
			(start -0.3048 -0.1016)
			(end 0.3048 -0.1016)
			(stroke
				(width 0.1)
				(type default)
			)
			(layer "B.Fab")
		)
		(fp_line
			(start 0.3048 -0.1016)
			(end 0.3048 0.9906)
			(stroke
				(width 0.1)
				(type default)
			)
			(layer "B.Fab")
		)
		(pad "1" smd rect
			(at 0 0 90)
			(size 0.508 0.508)
			(layers "B.Cu" "B.Mask" "B.Paste")
			(net "P3V3")
		)
		(pad "2" smd rect
			(at 0 0.889 90)
			(size 0.508 0.508)
			(layers "B.Cu" "B.Mask" "B.Paste")
			(net "GND")
		)
		(zone
			(layer "B.Cu")
			(hatch none 0.5)
			(connect_pads
				(clearance 0)
			)
			(min_thickness 0.25)
			(keepout
				(tracks not_allowed)
				(vias allowed)
				(pads allowed)
				(copperpour not_allowed)
				(footprints allowed)
			)
			(placement
				(enabled no)
				(sheetname "")
			)
			(fill
				(thermal_gap 0.5)
				(thermal_bridge_width 0.5)
				(island_removal_mode 0)
			)
			(polygon
				(pts
					(xy 390.0805 -39.25951) (xy 390.0805 -39.76751) (xy 390.4615 -39.76751) (xy 390.4615 -39.25951)
				)
			)
		)
		(zone
			(layer "B.Cu")
			(hatch none 0.5)
			(connect_pads
				(clearance 0)
			)
			(min_thickness 0.25)
			(keepout
				(tracks allowed)
				(vias not_allowed)
				(pads allowed)
				(copperpour not_allowed)
				(footprints allowed)
			)
			(placement
				(enabled no)
				(sheetname "")
			)
			(fill
				(thermal_gap 0.5)
				(thermal_bridge_width 0.5)
				(island_removal_mode 0)
			)
			(polygon
				(pts
					(xy 390.4615 -39.25951) (xy 390.4615 -39.76751) (xy 390.0805 -39.76751) (xy 390.0805 -39.25951)
				)
			)
		)
	)
)
